(kicad_pcb
	(version 20260206)
	(generator "pcbnew")
	(generator_version "10.0")
	(general
		(thickness 1.6)
		(legacy_teardrops no)
	)
	(paper "A4")
	(title_block
		(title "04192023_DAF0TMB3IC0_F0TG_MB_C_brd_V02_OCP.brd")
		(comment 1 "Grand Teton / footprints 4775-4781 of 8354")
	)
	(layers
		(0 "F.Cu" signal "TOP")
		(4 "In1.Cu" signal "GND")
		(6 "In2.Cu" signal "IN1")
		(8 "In3.Cu" signal "GND1")
		(10 "In4.Cu" signal "IN2")
		(12 "In5.Cu" signal "GND2")
		(14 "In6.Cu" signal "IN3")
		(16 "In7.Cu" signal "GND3")
		(18 "In8.Cu" signal "VCC")
		(20 "In9.Cu" signal "VCC1")
		(22 "In10.Cu" signal "GND4")
		(24 "In11.Cu" signal "IN4")
		(26 "In12.Cu" signal "GND5")
		(28 "In13.Cu" signal "IN5")
		(30 "In14.Cu" signal "GND6")
		(32 "In15.Cu" signal "IN6")
		(34 "In16.Cu" signal "GND7")
		(2 "B.Cu" signal "BOTTOM")
		(9 "F.Adhes" user "F.Adhesive")
		(11 "B.Adhes" user "B.Adhesive")
		(13 "F.Paste" user "Package Geometry/Pastemask Top")
		(15 "B.Paste" user "Package Geometry/Pastemask Bottom")
		(5 "F.SilkS" user "Ref Des/Silkscreen Top")
		(7 "B.SilkS" user "Ref Des/Silkscreen Bottom")
		(1 "F.Mask" user "Board Geometry/Soldermask Top")
		(3 "B.Mask" user "Board Geometry/Soldermask Bottom")
		(17 "Dwgs.User" user "User.Drawings")
		(19 "Cmts.User" user "User.Comments")
		(21 "Eco1.User" user "User.Eco1")
		(23 "Eco2.User" user "User.Eco2")
		(25 "Edge.Cuts" user "Board Geometry/Outline")
		(27 "Margin" user)
		(31 "F.CrtYd" user "Package Geometry/Place Bound Top")
		(29 "B.CrtYd" user "Package Geometry/Place Bound Bottom")
		(35 "F.Fab" user "Ref Des/Assembly Top")
		(33 "B.Fab" user "Ref Des/Assembly Bottom")
	)
	(footprint ""
		(layer "F.Cu")
		(at 305.082448 -147.940522 180)
		(property "Reference" "R5014"
			(at 0 0 180)
			(layer "F.SilkS")
			(hide yes)
			(effects
				(font
					(size 1.27 1.27)
				)
			)
		)
		(property "Value" ""
			(at 0 0 180)
			(layer "F.Fab")
			(effects
				(font
					(size 1.27 1.27)
				)
			)
		)
		(duplicate_pad_numbers_are_jumpers no)
		(fp_line
			(start 0.7874 0.4064)
			(end -0.7874 0.4064)
			(stroke
				(width 0.1524)
				(type default)
			)
			(layer "F.SilkS")
		)
		(fp_line
			(start 0.7874 -0.4064)
			(end 0.7874 0.4064)
			(stroke
				(width 0.1524)
				(type default)
			)
			(layer "F.SilkS")
		)
		(fp_line
			(start -0.7874 0.4064)
			(end -0.7874 -0.4064)
			(stroke
				(width 0.1524)
				(type default)
			)
			(layer "F.SilkS")
		)
		(fp_line
			(start -0.7874 -0.4064)
			(end 0.7874 -0.4064)
			(stroke
				(width 0.1524)
				(type default)
			)
			(layer "F.SilkS")
		)
		(fp_line
			(start 0.67945 0.3048)
			(end 0.120396 0.3048)
			(stroke
				(width 0.1)
				(type default)
			)
			(layer "F.Fab")
		)
		(fp_line
			(start 0.67945 -0.3048)
			(end 0.67945 0.3048)
			(stroke
				(width 0.1)
				(type default)
			)
			(layer "F.Fab")
		)
		(fp_line
			(start 0.12065 -0.2794)
			(end 0.12065 -0.3048)
			(stroke
				(width 0.1)
				(type default)
			)
			(layer "F.Fab")
		)
		(fp_line
			(start 0.12065 -0.3048)
			(end 0.67945 -0.3048)
			(stroke
				(width 0.1)
				(type default)
			)
			(layer "F.Fab")
		)
		(fp_line
			(start 0.120396 0.3048)
			(end 0.120396 0.2794)
			(stroke
				(width 0.1)
				(type default)
			)
			(layer "F.Fab")
		)
		(fp_line
			(start 0.120396 0.2794)
			(end -0.12065 0.2794)
			(stroke
				(width 0.1)
				(type default)
			)
			(layer "F.Fab")
		)
		(fp_line
			(start -0.12065 0.3048)
			(end -0.67945 0.3048)
			(stroke
				(width 0.1)
				(type default)
			)
			(layer "F.Fab")
		)
		(fp_line
			(start -0.12065 0.2794)
			(end -0.12065 0.3048)
			(stroke
				(width 0.1)
				(type default)
			)
			(layer "F.Fab")
		)
		(fp_line
			(start -0.12065 -0.2794)
			(end 0.12065 -0.2794)
			(stroke
				(width 0.1)
				(type default)
			)
			(layer "F.Fab")
		)
		(fp_line
			(start -0.12065 -0.305054)
			(end -0.12065 -0.2794)
			(stroke
				(width 0.1)
				(type default)
			)
			(layer "F.Fab")
		)
		(fp_line
			(start -0.67945 0.3048)
			(end -0.67945 -0.305054)
			(stroke
				(width 0.1)
				(type default)
			)
			(layer "F.Fab")
		)
		(fp_line
			(start -0.67945 -0.305054)
			(end -0.12065 -0.305054)
			(stroke
				(width 0.1)
				(type default)
			)
			(layer "F.Fab")
		)
		(pad "1" smd circle
			(at -0.40005 0 180)
			(size 0 0)
			(layers "F.Cu" "F.Mask" "F.Paste")
			(net "PVDD11_S3_P0")
		)
		(pad "2" smd circle
			(at 0.40005 0 180)
			(size 0 0)
			(layers "F.Cu" "F.Mask" "F.Paste")
			(net "I3C_SCM_0_R_SCL")
		)
	)
	(footprint ""
		(layer "F.Cu")
		(at 109.918754 -326.566276 180)
		(property "Reference" "PR228"
			(at 0 0 180)
			(layer "F.SilkS")
			(hide yes)
			(effects
				(font
					(size 1.27 1.27)
				)
			)
		)
		(property "Value" ""
			(at 0 0 180)
			(layer "F.Fab")
			(effects
				(font
					(size 1.27 1.27)
				)
			)
		)
		(duplicate_pad_numbers_are_jumpers no)
		(fp_line
			(start 0.7874 0.4064)
			(end -0.7874 0.4064)
			(stroke
				(width 0.1524)
				(type default)
			)
			(layer "F.SilkS")
		)
		(fp_line
			(start 0.7874 -0.4064)
			(end 0.7874 0.4064)
			(stroke
				(width 0.1524)
				(type default)
			)
			(layer "F.SilkS")
		)
		(fp_line
			(start -0.7874 0.4064)
			(end -0.7874 -0.4064)
			(stroke
				(width 0.1524)
				(type default)
			)
			(layer "F.SilkS")
		)
		(fp_line
			(start -0.7874 -0.4064)
			(end 0.7874 -0.4064)
			(stroke
				(width 0.1524)
				(type default)
			)
			(layer "F.SilkS")
		)
		(fp_line
			(start 0.67945 0.3048)
			(end 0.120396 0.3048)
			(stroke
				(width 0.1)
				(type default)
			)
			(layer "F.Fab")
		)
		(fp_line
			(start 0.67945 -0.3048)
			(end 0.67945 0.3048)
			(stroke
				(width 0.1)
				(type default)
			)
			(layer "F.Fab")
		)
		(fp_line
			(start 0.12065 -0.2794)
			(end 0.12065 -0.3048)
			(stroke
				(width 0.1)
				(type default)
			)
			(layer "F.Fab")
		)
		(fp_line
			(start 0.12065 -0.3048)
			(end 0.67945 -0.3048)
			(stroke
				(width 0.1)
				(type default)
			)
			(layer "F.Fab")
		)
		(fp_line
			(start 0.120396 0.3048)
			(end 0.120396 0.2794)
			(stroke
				(width 0.1)
				(type default)
			)
			(layer "F.Fab")
		)
		(fp_line
			(start 0.120396 0.2794)
			(end -0.12065 0.2794)
			(stroke
				(width 0.1)
				(type default)
			)
			(layer "F.Fab")
		)
		(fp_line
			(start -0.12065 0.3048)
			(end -0.67945 0.3048)
			(stroke
				(width 0.1)
				(type default)
			)
			(layer "F.Fab")
		)
		(fp_line
			(start -0.12065 0.2794)
			(end -0.12065 0.3048)
			(stroke
				(width 0.1)
				(type default)
			)
			(layer "F.Fab")
		)
		(fp_line
			(start -0.12065 -0.2794)
			(end 0.12065 -0.2794)
			(stroke
				(width 0.1)
				(type default)
			)
			(layer "F.Fab")
		)
		(fp_line
			(start -0.12065 -0.305054)
			(end -0.12065 -0.2794)
			(stroke
				(width 0.1)
				(type default)
			)
			(layer "F.Fab")
		)
		(fp_line
			(start -0.67945 0.3048)
			(end -0.67945 -0.305054)
			(stroke
				(width 0.1)
				(type default)
			)
			(layer "F.Fab")
		)
		(fp_line
			(start -0.67945 -0.305054)
			(end -0.12065 -0.305054)
			(stroke
				(width 0.1)
				(type default)
			)
			(layer "F.Fab")
		)
		(pad "1" smd circle
			(at -0.40005 0 180)
			(size 0 0)
			(layers "F.Cu" "F.Mask" "F.Paste")
			(net "VSENSE_PVDDCR_CPU1_P1_DP")
		)
		(pad "2" smd circle
			(at 0.40005 0 180)
			(size 0 0)
			(layers "F.Cu" "F.Mask" "F.Paste")
			(net "PVDDCR_CPU1_P1")
		)
	)
	(footprint ""
		(layer "F.Cu")
		(at 177.40757 -425.304966)
		(property "Reference" "R2982"
			(at 0 0 0)
			(layer "F.SilkS")
			(hide yes)
			(effects
				(font
					(size 1.27 1.27)
				)
			)
		)
		(property "Value" ""
			(at 0 0 0)
			(layer "F.Fab")
			(effects
				(font
					(size 1.27 1.27)
				)
			)
		)
		(duplicate_pad_numbers_are_jumpers no)
		(fp_line
			(start -0.7874 -0.4064)
			(end 0.7874 -0.4064)
			(stroke
				(width 0.1524)
				(type default)
			)
			(layer "F.SilkS")
		)
		(fp_line
			(start -0.7874 0.4064)
			(end -0.7874 -0.4064)
			(stroke
				(width 0.1524)
				(type default)
			)
			(layer "F.SilkS")
		)
		(fp_line
			(start 0.7874 -0.4064)
			(end 0.7874 0.4064)
			(stroke
				(width 0.1524)
				(type default)
			)
			(layer "F.SilkS")
		)
		(fp_line
			(start 0.7874 0.4064)
			(end -0.7874 0.4064)
			(stroke
				(width 0.1524)
				(type default)
			)
			(layer "F.SilkS")
		)
		(fp_line
			(start -0.67945 -0.305054)
			(end -0.12065 -0.305054)
			(stroke
				(width 0.1)
				(type default)
			)
			(layer "F.Fab")
		)
		(fp_line
			(start -0.67945 0.3048)
			(end -0.67945 -0.305054)
			(stroke
				(width 0.1)
				(type default)
			)
			(layer "F.Fab")
		)
		(fp_line
			(start -0.12065 -0.305054)
			(end -0.12065 -0.2794)
			(stroke
				(width 0.1)
				(type default)
			)
			(layer "F.Fab")
		)
		(fp_line
			(start -0.12065 -0.2794)
			(end 0.12065 -0.2794)
			(stroke
				(width 0.1)
				(type default)
			)
			(layer "F.Fab")
		)
		(fp_line
			(start -0.12065 0.2794)
			(end -0.12065 0.3048)
			(stroke
				(width 0.1)
				(type default)
			)
			(layer "F.Fab")
		)
		(fp_line
			(start -0.12065 0.3048)
			(end -0.67945 0.3048)
			(stroke
				(width 0.1)
				(type default)
			)
			(layer "F.Fab")
		)
		(fp_line
			(start 0.120396 0.2794)
			(end -0.12065 0.2794)
			(stroke
				(width 0.1)
				(type default)
			)
			(layer "F.Fab")
		)
		(fp_line
			(start 0.120396 0.3048)
			(end 0.120396 0.2794)
			(stroke
				(width 0.1)
				(type default)
			)
			(layer "F.Fab")
		)
		(fp_line
			(start 0.12065 -0.3048)
			(end 0.67945 -0.3048)
			(stroke
				(width 0.1)
				(type default)
			)
			(layer "F.Fab")
		)
		(fp_line
			(start 0.12065 -0.2794)
			(end 0.12065 -0.3048)
			(stroke
				(width 0.1)
				(type default)
			)
			(layer "F.Fab")
		)
		(fp_line
			(start 0.67945 -0.3048)
			(end 0.67945 0.3048)
			(stroke
				(width 0.1)
				(type default)
			)
			(layer "F.Fab")
		)
		(fp_line
			(start 0.67945 0.3048)
			(end 0.120396 0.3048)
			(stroke
				(width 0.1)
				(type default)
			)
			(layer "F.Fab")
		)
		(pad "1" smd circle
			(at -0.40005 0)
			(size 0 0)
			(layers "F.Cu" "F.Mask" "F.Paste")
			(net "SMB_IOEXP_3V3AUX_SCL")
		)
		(pad "2" smd circle
			(at 0.40005 0)
			(size 0 0)
			(layers "F.Cu" "F.Mask" "F.Paste")
			(net "SMB_IOEXP_3V3AUX_SCL_R1")
		)
	)
	(footprint ""
		(layer "F.Cu")
		(at 75.7936 -383.7432)
		(property "Reference" "R791"
			(at 0 0 0)
			(layer "F.SilkS")
			(hide yes)
			(effects
				(font
					(size 1.27 1.27)
				)
			)
		)
		(property "Value" ""
			(at 0 0 0)
			(layer "F.Fab")
			(effects
				(font
					(size 1.27 1.27)
				)
			)
		)
		(duplicate_pad_numbers_are_jumpers no)
		(fp_line
			(start -0.32512 -0.175006)
			(end 0.32512 -0.175006)
			(stroke
				(width 0.1)
				(type default)
			)
			(layer "F.Fab")
		)
		(fp_line
			(start -0.32512 0.175006)
			(end -0.32512 -0.175006)
			(stroke
				(width 0.1)
				(type default)
			)
			(layer "F.Fab")
		)
		(fp_line
			(start 0.32512 -0.175006)
			(end 0.32512 0.175006)
			(stroke
				(width 0.1)
				(type default)
			)
			(layer "F.Fab")
		)
		(fp_line
			(start 0.32512 0.175006)
			(end -0.32512 0.175006)
			(stroke
				(width 0.1)
				(type default)
			)
			(layer "F.Fab")
		)
		(pad "1" smd rect
			(at -0.2667 0)
			(size 0.3048 0.381)
			(layers "F.Cu" "F.Mask" "F.Paste")
			(net "TEST2_RT_CPU1_P1")
		)
		(pad "2" smd rect
			(at 0.2667 0 180)
			(size 0.3048 0.381)
			(layers "F.Cu" "F.Mask" "F.Paste")
			(net "GND")
		)
	)
	(footprint ""
		(layer "F.Cu")
		(at 205.214982 -116.673376 180)
		(property "Reference" "R4557"
			(at 0 0 180)
			(layer "F.SilkS")
			(hide yes)
			(effects
				(font
					(size 1.27 1.27)
				)
			)
		)
		(property "Value" ""
			(at 0 0 180)
			(layer "F.Fab")
			(effects
				(font
					(size 1.27 1.27)
				)
			)
		)
		(duplicate_pad_numbers_are_jumpers no)
		(fp_line
			(start 0.7874 0.4064)
			(end -0.7874 0.4064)
			(stroke
				(width 0.1524)
				(type default)
			)
			(layer "F.SilkS")
		)
		(fp_line
			(start 0.7874 -0.4064)
			(end 0.7874 0.4064)
			(stroke
				(width 0.1524)
				(type default)
			)
			(layer "F.SilkS")
		)
		(fp_line
			(start -0.7874 0.4064)
			(end -0.7874 -0.4064)
			(stroke
				(width 0.1524)
				(type default)
			)
			(layer "F.SilkS")
		)
		(fp_line
			(start -0.7874 -0.4064)
			(end 0.7874 -0.4064)
			(stroke
				(width 0.1524)
				(type default)
			)
			(layer "F.SilkS")
		)
		(fp_line
			(start 0.67945 0.3048)
			(end 0.120396 0.3048)
			(stroke
				(width 0.1)
				(type default)
			)
			(layer "F.Fab")
		)
		(fp_line
			(start 0.67945 -0.3048)
			(end 0.67945 0.3048)
			(stroke
				(width 0.1)
				(type default)
			)
			(layer "F.Fab")
		)
		(fp_line
			(start 0.12065 -0.2794)
			(end 0.12065 -0.3048)
			(stroke
				(width 0.1)
				(type default)
			)
			(layer "F.Fab")
		)
		(fp_line
			(start 0.12065 -0.3048)
			(end 0.67945 -0.3048)
			(stroke
				(width 0.1)
				(type default)
			)
			(layer "F.Fab")
		)
		(fp_line
			(start 0.120396 0.3048)
			(end 0.120396 0.2794)
			(stroke
				(width 0.1)
				(type default)
			)
			(layer "F.Fab")
		)
		(fp_line
			(start 0.120396 0.2794)
			(end -0.12065 0.2794)
			(stroke
				(width 0.1)
				(type default)
			)
			(layer "F.Fab")
		)
		(fp_line
			(start -0.12065 0.3048)
			(end -0.67945 0.3048)
			(stroke
				(width 0.1)
				(type default)
			)
			(layer "F.Fab")
		)
		(fp_line
			(start -0.12065 0.2794)
			(end -0.12065 0.3048)
			(stroke
				(width 0.1)
				(type default)
			)
			(layer "F.Fab")
		)
		(fp_line
			(start -0.12065 -0.2794)
			(end 0.12065 -0.2794)
			(stroke
				(width 0.1)
				(type default)
			)
			(layer "F.Fab")
		)
		(fp_line
			(start -0.12065 -0.305054)
			(end -0.12065 -0.2794)
			(stroke
				(width 0.1)
				(type default)
			)
			(layer "F.Fab")
		)
		(fp_line
			(start -0.67945 0.3048)
			(end -0.67945 -0.305054)
			(stroke
				(width 0.1)
				(type default)
			)
			(layer "F.Fab")
		)
		(fp_line
			(start -0.67945 -0.305054)
			(end -0.12065 -0.305054)
			(stroke
				(width 0.1)
				(type default)
			)
			(layer "F.Fab")
		)
		(pad "1" smd circle
			(at -0.40005 0 180)
			(size 0 0)
			(layers "F.Cu" "F.Mask" "F.Paste")
			(net "HPDB_HSC_PWRGD_ISO")
		)
		(pad "2" smd circle
			(at 0.40005 0 180)
			(size 0 0)
			(layers "F.Cu" "F.Mask" "F.Paste")
			(net "HPDB_HSC_PWRGD_ISO_R")
		)
	)
	(footprint ""
		(layer "F.Cu")
		(at 330.374244 -335.129632 -90)
		(property "Reference" "PC88_2"
			(at 0 0 270)
			(layer "F.SilkS")
			(hide yes)
			(effects
				(font
					(size 1.27 1.27)
				)
			)
		)
		(property "Value" ""
			(at 0 0 270)
			(layer "F.Fab")
			(effects
				(font
					(size 1.27 1.27)
				)
			)
		)
		(duplicate_pad_numbers_are_jumpers no)
		(fp_line
			(start -0.7874 0.4064)
			(end -0.7874 -0.4064)
			(stroke
				(width 0.1524)
				(type default)
			)
			(layer "F.SilkS")
		)
		(fp_line
			(start 0.7874 0.4064)
			(end -0.7874 0.4064)
			(stroke
				(width 0.1524)
				(type default)
			)
			(layer "F.SilkS")
		)
		(fp_line
			(start -0.7874 -0.4064)
			(end 0.7874 -0.4064)
			(stroke
				(width 0.1524)
				(type default)
			)
			(layer "F.SilkS")
		)
		(fp_line
			(start 0.7874 -0.4064)
			(end 0.7874 0.4064)
			(stroke
				(width 0.1524)
				(type default)
			)
			(layer "F.SilkS")
		)
		(fp_line
			(start -0.67945 0.3048)
			(end -0.67945 -0.305054)
			(stroke
				(width 0.1)
				(type default)
			)
			(layer "F.Fab")
		)
		(fp_line
			(start -0.12065 0.3048)
			(end -0.67945 0.3048)
			(stroke
				(width 0.1)
				(type default)
			)
			(layer "F.Fab")
		)
		(fp_line
			(start 0.120396 0.3048)
			(end 0.120396 0.2794)
			(stroke
				(width 0.1)
				(type default)
			)
			(layer "F.Fab")
		)
		(fp_line
			(start 0.67945 0.3048)
			(end 0.120396 0.3048)
			(stroke
				(width 0.1)
				(type default)
			)
			(layer "F.Fab")
		)
		(fp_line
			(start -0.12065 0.2794)
			(end -0.12065 0.3048)
			(stroke
				(width 0.1)
				(type default)
			)
			(layer "F.Fab")
		)
		(fp_line
			(start 0.120396 0.2794)
			(end -0.12065 0.2794)
			(stroke
				(width 0.1)
				(type default)
			)
			(layer "F.Fab")
		)
		(fp_line
			(start -0.12065 -0.2794)
			(end 0.12065 -0.2794)
			(stroke
				(width 0.1)
				(type default)
			)
			(layer "F.Fab")
		)
		(fp_line
			(start 0.12065 -0.2794)
			(end 0.12065 -0.3048)
			(stroke
				(width 0.1)
				(type default)
			)
			(layer "F.Fab")
		)
		(fp_line
			(start 0.12065 -0.3048)
			(end 0.67945 -0.3048)
			(stroke
				(width 0.1)
				(type default)
			)
			(layer "F.Fab")
		)
		(fp_line
			(start 0.67945 -0.3048)
			(end 0.67945 0.3048)
			(stroke
				(width 0.1)
				(type default)
			)
			(layer "F.Fab")
		)
		(fp_line
			(start -0.67945 -0.305054)
			(end -0.12065 -0.305054)
			(stroke
				(width 0.1)
				(type default)
			)
			(layer "F.Fab")
		)
		(fp_line
			(start -0.12065 -0.305054)
			(end -0.12065 -0.2794)
			(stroke
				(width 0.1)
				(type default)
			)
			(layer "F.Fab")
		)
		(pad "1" smd circle
			(at -0.40005 0 270)
			(size 0 0)
			(layers "F.Cu" "F.Mask" "F.Paste")
			(net "SW_P12V_AUX_PVDDCR_CPU1_P0_FLT")
		)
		(pad "2" smd circle
			(at 0.40005 0 270)
			(size 0 0)
			(layers "F.Cu" "F.Mask" "F.Paste")
			(net "GND")
		)
	)
	(footprint ""
		(layer "F.Cu")
		(at 437.542432 -27.275536 90)
		(property "Reference" "PR3841"
			(at 0 0 90)
			(layer "F.SilkS")
			(hide yes)
			(effects
				(font
					(size 1.27 1.27)
				)
			)
		)
		(property "Value" ""
			(at 0 0 90)
			(layer "F.Fab")
			(effects
				(font
					(size 1.27 1.27)
				)
			)
		)
		(duplicate_pad_numbers_are_jumpers no)
		(fp_line
			(start 0.7874 -0.4064)
			(end 0.7874 0.4064)
			(stroke
				(width 0.1524)
				(type default)
			)
			(layer "F.SilkS")
		)
		(fp_line
			(start -0.7874 -0.4064)
			(end 0.7874 -0.4064)
			(stroke
				(width 0.1524)
				(type default)
			)
			(layer "F.SilkS")
		)
		(fp_line
			(start 0.7874 0.4064)
			(end -0.7874 0.4064)
			(stroke
				(width 0.1524)
				(type default)
			)
			(layer "F.SilkS")
		)
		(fp_line
			(start -0.7874 0.4064)
			(end -0.7874 -0.4064)
			(stroke
				(width 0.1524)
				(type default)
			)
			(layer "F.SilkS")
		)
		(fp_line
			(start -0.12065 -0.305054)
			(end -0.12065 -0.2794)
			(stroke
				(width 0.1)
				(type default)
			)
			(layer "F.Fab")
		)
		(fp_line
			(start -0.67945 -0.305054)
			(end -0.12065 -0.305054)
			(stroke
				(width 0.1)
				(type default)
			)
			(layer "F.Fab")
		)
		(fp_line
			(start 0.67945 -0.3048)
			(end 0.67945 0.3048)
			(stroke
				(width 0.1)
				(type default)
			)
			(layer "F.Fab")
		)
		(fp_line
			(start 0.12065 -0.3048)
			(end 0.67945 -0.3048)
			(stroke
				(width 0.1)
				(type default)
			)
			(layer "F.Fab")
		)
		(fp_line
			(start 0.12065 -0.2794)
			(end 0.12065 -0.3048)
			(stroke
				(width 0.1)
				(type default)
			)
			(layer "F.Fab")
		)
		(fp_line
			(start -0.12065 -0.2794)
			(end 0.12065 -0.2794)
			(stroke
				(width 0.1)
				(type default)
			)
			(layer "F.Fab")
		)
		(fp_line
			(start 0.120396 0.2794)
			(end -0.12065 0.2794)
			(stroke
				(width 0.1)
				(type default)
			)
			(layer "F.Fab")
		)
		(fp_line
			(start -0.12065 0.2794)
			(end -0.12065 0.3048)
			(stroke
				(width 0.1)
				(type default)
			)
			(layer "F.Fab")
		)
		(fp_line
			(start 0.67945 0.3048)
			(end 0.120396 0.3048)
			(stroke
				(width 0.1)
				(type default)
			)
			(layer "F.Fab")
		)
		(fp_line
			(start 0.120396 0.3048)
			(end 0.120396 0.2794)
			(stroke
				(width 0.1)
				(type default)
			)
			(layer "F.Fab")
		)
		(fp_line
			(start -0.12065 0.3048)
			(end -0.67945 0.3048)
			(stroke
				(width 0.1)
				(type default)
			)
			(layer "F.Fab")
		)
		(fp_line
			(start -0.67945 0.3048)
			(end -0.67945 -0.305054)
			(stroke
				(width 0.1)
				(type default)
			)
			(layer "F.Fab")
		)
		(pad "1" smd circle
			(at -0.40005 0 90)
			(size 0 0)
			(layers "F.Cu" "F.Mask" "F.Paste")
			(net "P12V_AUX")
		)
		(pad "2" smd circle
			(at 0.40005 0 90)
			(size 0 0)
			(layers "F.Cu" "F.Mask" "F.Paste")
			(net "P12V_OCP_OV_FB_1")
		)
	)
)
